# T6G (Grand Teton) — schematic netlist excerpt (pin names and nets, part order shuffled) for the footprints in the layout excerpt that follows; sources: Cadence DE-HDL packaged netlist, KiCad conversion of 04192023_DAF0TMB3IC0_F0TG_MB_C_brd_V02_OCP.brd

C2392  Q_CAP  22UF 4V 20% X6S  pkg C0402  page 73 : A = PVDDCR_CPU1_P1 ; B = GND
R6503  Q_RES  2.2K 5% CHIP  pkg 0402LF  page 55 : A = CPU1_FORCE_SELFREFRESH ; B = GND
PC214_2  Q_CAP  22UF 16V 20% X6S  pkg C0805  page 208 : A = SW_P12V_AUX_PVDD11_S3_P0_FLT ; B = GND

(kicad_pcb
	(version 20260206)
	(generator "pcbnew")
	(generator_version "10.0")
	(general
		(thickness 1.6)
		(legacy_teardrops no)
	)
	(paper "A4")
	(title_block
		(title "04192023_DAF0TMB3IC0_F0TG_MB_C_brd_V02_OCP.brd")
		(comment 1 "Grand Teton / footprints 6566-6568 of 8354")
	)
	(layers
		(0 "F.Cu" signal "TOP")
		(4 "In1.Cu" signal "GND")
		(6 "In2.Cu" signal "IN1")
		(8 "In3.Cu" signal "GND1")
		(10 "In4.Cu" signal "IN2")
		(12 "In5.Cu" signal "GND2")
		(14 "In6.Cu" signal "IN3")
		(16 "In7.Cu" signal "GND3")
		(18 "In8.Cu" signal "VCC")
		(20 "In9.Cu" signal "VCC1")
		(22 "In10.Cu" signal "GND4")
		(24 "In11.Cu" signal "IN4")
		(26 "In12.Cu" signal "GND5")
		(28 "In13.Cu" signal "IN5")
		(30 "In14.Cu" signal "GND6")
		(32 "In15.Cu" signal "IN6")
		(34 "In16.Cu" signal "GND7")
		(2 "B.Cu" signal "BOTTOM")
		(9 "F.Adhes" user "F.Adhesive")
		(11 "B.Adhes" user "B.Adhesive")
		(13 "F.Paste" user "Package Geometry/Pastemask Top")
		(15 "B.Paste" user "Package Geometry/Pastemask Bottom")
		(5 "F.SilkS" user "Ref Des/Silkscreen Top")
		(7 "B.SilkS" user "Ref Des/Silkscreen Bottom")
		(1 "F.Mask" user "Board Geometry/Soldermask Top")
		(3 "B.Mask" user "Board Geometry/Soldermask Bottom")
		(17 "Dwgs.User" user "User.Drawings")
		(19 "Cmts.User" user "User.Comments")
		(21 "Eco1.User" user "User.Eco1")
		(23 "Eco2.User" user "User.Eco2")
		(25 "Edge.Cuts" user "Board Geometry/Outline")
		(27 "Margin" user)
		(31 "F.CrtYd" user "Package Geometry/Place Bound Top")
		(29 "B.CrtYd" user "Package Geometry/Place Bound Bottom")
		(35 "F.Fab" user "Ref Des/Assembly Top")
		(33 "B.Fab" user "Ref Des/Assembly Bottom")
	)
	(footprint ""
		(layer "B.Cu")
		(at 67.201034 -196.95414)
		(property "Reference" "R6503"
			(at 0 0 0)
			(layer "B.SilkS")
			(hide yes)
			(effects
				(font
					(size 1.27 1.27)
				)
				(justify mirror)
			)
		)
		(property "Value" ""
			(at 0 0 0)
			(layer "B.Fab")
			(effects
				(font
					(size 1.27 1.27)
				)
				(justify mirror)
			)
		)
		(duplicate_pad_numbers_are_jumpers no)
		(fp_line
			(start -0.7874 -0.4064)
			(end -0.7874 0.4064)
			(stroke
				(width 0.1524)
				(type default)
			)
			(layer "B.SilkS")
		)
		(fp_line
			(start -0.7874 0.4064)
			(end 0.7874 0.4064)
			(stroke
				(width 0.1524)
				(type default)
			)
			(layer "B.SilkS")
		)
		(fp_line
			(start 0.7874 -0.4064)
			(end -0.7874 -0.4064)
			(stroke
				(width 0.1524)
				(type default)
			)
			(layer "B.SilkS")
		)
		(fp_line
			(start 0.7874 0.4064)
			(end 0.7874 -0.4064)
			(stroke
				(width 0.1524)
				(type default)
			)
			(layer "B.SilkS")
		)
		(fp_line
			(start -0.67945 -0.3048)
			(end -0.67945 0.3048)
			(stroke
				(width 0.1)
				(type default)
			)
			(layer "B.Fab")
		)
		(fp_line
			(start -0.67945 0.3048)
			(end -0.120396 0.3048)
			(stroke
				(width 0.1)
				(type default)
			)
			(layer "B.Fab")
		)
		(fp_line
			(start -0.12065 -0.3048)
			(end -0.67945 -0.3048)
			(stroke
				(width 0.1)
				(type default)
			)
			(layer "B.Fab")
		)
		(fp_line
			(start -0.12065 -0.2794)
			(end -0.12065 -0.3048)
			(stroke
				(width 0.1)
				(type default)
			)
			(layer "B.Fab")
		)
		(fp_line
			(start -0.120396 0.2794)
			(end 0.12065 0.2794)
			(stroke
				(width 0.1)
				(type default)
			)
			(layer "B.Fab")
		)
		(fp_line
			(start -0.120396 0.3048)
			(end -0.120396 0.2794)
			(stroke
				(width 0.1)
				(type default)
			)
			(layer "B.Fab")
		)
		(fp_line
			(start 0.12065 -0.305054)
			(end 0.12065 -0.2794)
			(stroke
				(width 0.1)
				(type default)
			)
			(layer "B.Fab")
		)
		(fp_line
			(start 0.12065 -0.2794)
			(end -0.12065 -0.2794)
			(stroke
				(width 0.1)
				(type default)
			)
			(layer "B.Fab")
		)
		(fp_line
			(start 0.12065 0.2794)
			(end 0.12065 0.3048)
			(stroke
				(width 0.1)
				(type default)
			)
			(layer "B.Fab")
		)
		(fp_line
			(start 0.12065 0.3048)
			(end 0.67945 0.3048)
			(stroke
				(width 0.1)
				(type default)
			)
			(layer "B.Fab")
		)
		(fp_line
			(start 0.67945 -0.305054)
			(end 0.12065 -0.305054)
			(stroke
				(width 0.1)
				(type default)
			)
			(layer "B.Fab")
		)
		(fp_line
			(start 0.67945 0.3048)
			(end 0.67945 -0.305054)
			(stroke
				(width 0.1)
				(type default)
			)
			(layer "B.Fab")
		)
		(pad "1" smd circle
			(at 0.40005 0 180)
			(size 0 0)
			(layers "B.Cu" "B.Mask" "B.Paste")
			(net "CPU1_FORCE_SELFREFRESH")
		)
		(pad "2" smd circle
			(at -0.40005 0 180)
			(size 0 0)
			(layers "B.Cu" "B.Mask" "B.Paste")
			(net "GND")
		)
	)
	(footprint ""
		(layer "B.Cu")
		(at 432.997102 -351.058226 90)
		(property "Reference" "PC214_2"
			(at 0 0 90)
			(layer "B.SilkS")
			(hide yes)
			(effects
				(font
					(size 1.27 1.27)
				)
				(justify mirror)
			)
		)
		(property "Value" ""
			(at 0 0 90)
			(layer "B.Fab")
			(effects
				(font
					(size 1.27 1.27)
				)
				(justify mirror)
			)
		)
		(duplicate_pad_numbers_are_jumpers no)
		(fp_line
			(start 1.524 -0.762)
			(end -1.524 -0.762)
			(stroke
				(width 0.1524)
				(type default)
			)
			(layer "B.SilkS")
		)
		(fp_line
			(start -1.524 -0.762)
			(end -1.524 0.762)
			(stroke
				(width 0.1524)
				(type default)
			)
			(layer "B.SilkS")
		)
		(fp_line
			(start 1.524 0.762)
			(end 1.524 -0.762)
			(stroke
				(width 0.1524)
				(type default)
			)
			(layer "B.SilkS")
		)
		(fp_line
			(start -1.524 0.762)
			(end 1.524 0.762)
			(stroke
				(width 0.1524)
				(type default)
			)
			(layer "B.SilkS")
		)
		(fp_line
			(start 1.1049 -0.724916)
			(end 1.1049 0.724916)
			(stroke
				(width 0.1)
				(type default)
			)
			(layer "B.Fab")
		)
		(fp_line
			(start -1.1049 -0.724916)
			(end 1.1049 -0.724916)
			(stroke
				(width 0.1)
				(type default)
			)
			(layer "B.Fab")
		)
		(fp_line
			(start 1.1049 0.724916)
			(end -1.1049 0.724916)
			(stroke
				(width 0.1)
				(type default)
			)
			(layer "B.Fab")
		)
		(fp_line
			(start -1.1049 0.724916)
			(end -1.1049 -0.724916)
			(stroke
				(width 0.1)
				(type default)
			)
			(layer "B.Fab")
		)
		(pad "1" smd rect
			(at 0.889 0 90)
			(size 1.016 1.27)
			(layers "B.Cu" "B.Mask" "B.Paste")
			(net "SW_P12V_AUX_PVDD11_S3_P0_FLT")
		)
		(pad "2" smd rect
			(at -0.889 0 90)
			(size 1.016 1.27)
			(layers "B.Cu" "B.Mask" "B.Paste")
			(net "GND")
		)
	)
	(footprint ""
		(layer "B.Cu")
		(at 117.83314 -267.529564)
		(property "Reference" "C2392"
			(at 0 0 0)
			(layer "B.SilkS")
			(hide yes)
			(effects
				(font
					(size 1.27 1.27)
				)
				(justify mirror)
			)
		)
		(property "Value" ""
			(at 0 0 0)
			(layer "B.Fab")
			(effects
				(font
					(size 1.27 1.27)
				)
				(justify mirror)
			)
		)
		(duplicate_pad_numbers_are_jumpers no)
		(fp_line
			(start -0.7874 -0.4064)
			(end -0.7874 0.4064)
			(stroke
				(width 0.1524)
				(type default)
			)
			(layer "B.SilkS")
		)
		(fp_line
			(start -0.7874 0.4064)
			(end 0.7874 0.4064)
			(stroke
				(width 0.1524)
				(type default)
			)
			(layer "B.SilkS")
		)
		(fp_line
			(start 0.7874 -0.4064)
			(end -0.7874 -0.4064)
			(stroke
				(width 0.1524)
				(type default)
			)
			(layer "B.SilkS")
		)
		(fp_line
			(start 0.7874 0.4064)
			(end 0.7874 -0.4064)
			(stroke
				(width 0.1524)
				(type default)
			)
			(layer "B.SilkS")
		)
		(fp_line
			(start -0.67945 -0.3048)
			(end -0.67945 0.3048)
			(stroke
				(width 0.1)
				(type default)
			)
			(layer "B.Fab")
		)
		(fp_line
			(start -0.67945 0.3048)
			(end -0.120396 0.3048)
			(stroke
				(width 0.1)
				(type default)
			)
			(layer "B.Fab")
		)
		(fp_line
			(start -0.12065 -0.3048)
			(end -0.67945 -0.3048)
			(stroke
				(width 0.1)
				(type default)
			)
			(layer "B.Fab")
		)
		(fp_line
			(start -0.12065 -0.2794)
			(end -0.12065 -0.3048)
			(stroke
				(width 0.1)
				(type default)
			)
			(layer "B.Fab")
		)
		(fp_line
			(start -0.120396 0.2794)
			(end 0.12065 0.2794)
			(stroke
				(width 0.1)
				(type default)
			)
			(layer "B.Fab")
		)
		(fp_line
			(start -0.120396 0.3048)
			(end -0.120396 0.2794)
			(stroke
				(width 0.1)
				(type default)
			)
			(layer "B.Fab")
		)
		(fp_line
			(start 0.12065 -0.305054)
			(end 0.12065 -0.2794)
			(stroke
				(width 0.1)
				(type default)
			)
			(layer "B.Fab")
		)
		(fp_line
			(start 0.12065 -0.2794)
			(end -0.12065 -0.2794)
			(stroke
				(width 0.1)
				(type default)
			)
			(layer "B.Fab")
		)
		(fp_line
			(start 0.12065 0.2794)
			(end 0.12065 0.3048)
			(stroke
				(width 0.1)
				(type default)
			)
			(layer "B.Fab")
		)
		(fp_line
			(start 0.12065 0.3048)
			(end 0.67945 0.3048)
			(stroke
				(width 0.1)
				(type default)
			)
			(layer "B.Fab")
		)
		(fp_line
			(start 0.67945 -0.305054)
			(end 0.12065 -0.305054)
			(stroke
				(width 0.1)
				(type default)
			)
			(layer "B.Fab")
		)
		(fp_line
			(start 0.67945 0.3048)
			(end 0.67945 -0.305054)
			(stroke
				(width 0.1)
				(type default)
			)
			(layer "B.Fab")
		)
		(pad "1" smd circle
			(at 0.40005 0 180)
			(size 0 0)
			(layers "B.Cu" "B.Mask" "B.Paste")
			(net "PVDDCR_CPU1_P1")
		)
		(pad "2" smd circle
			(at -0.40005 0 180)
			(size 0 0)
			(layers "B.Cu" "B.Mask" "B.Paste")
			(net "GND")
		)
	)
)
